# TIMECARD (Time Appliance Project (Time Card)) — schematic netlist excerpt (pin names and nets, part order shuffled) for the footprints in the layout excerpt that follows; sources: Cadence DE-HDL packaged netlist, KiCad conversion of R4006-B0001-02_R01.brd

R117  RESISTOR  33OHM 1%  pkg SMC_0402R_H016  page 22 : \1\ = GPSTP1_OUT ; \2\ = FPGA_IN_GPSTP1_OUT
L20  FERRITEBEAD  26OHM 25%  pkg SMC_0603R_H030  page 27 : \1\ = XP12R0V_PCIE ; \2\ = XP12R0V_IN

(kicad_pcb
	(version 20260206)
	(generator "pcbnew")
	(generator_version "10.0")
	(general
		(thickness 1.6)
		(legacy_teardrops no)
	)
	(paper "A4")
	(title_block
		(title "timecard-production-celestica-r4006 — R4006-B0001-02_R01.brd")
		(comment 1 "Time Appliance Project (Time Card) / footprints 619-620 of 1113")
	)
	(layers
		(0 "F.Cu" signal "TOP")
		(4 "In1.Cu" signal "L02_GND1")
		(6 "In2.Cu" signal "L03_SIG1")
		(8 "In3.Cu" signal "L04_GND2")
		(10 "In4.Cu" signal "L05_VCC1")
		(12 "In5.Cu" signal "L06_VCC2")
		(14 "In6.Cu" signal "L07_GND3")
		(16 "In7.Cu" signal "L08_SIG2")
		(18 "In8.Cu" signal "L09_GND4")
		(2 "B.Cu" signal "BOTTOM")
		(9 "F.Adhes" user "F.Adhesive")
		(11 "B.Adhes" user "B.Adhesive")
		(13 "F.Paste" user "Package Geometry/Pastemask Top")
		(15 "B.Paste" user "Package Geometry/Pastemask Bottom")
		(5 "F.SilkS" user "Ref Des/Silkscreen Top")
		(7 "B.SilkS" user "Ref Des/Silkscreen Bottom")
		(1 "F.Mask" user "Board Geometry/Soldermask Top")
		(3 "B.Mask" user "Board Geometry/Soldermask Bottom")
		(17 "Dwgs.User" user "User.Drawings")
		(19 "Cmts.User" user "User.Comments")
		(21 "Eco1.User" user "User.Eco1")
		(23 "Eco2.User" user "User.Eco2")
		(25 "Edge.Cuts" user "Board Geometry/Outline")
		(27 "Margin" user)
		(31 "F.CrtYd" user "Package Geometry/Place Bound Top")
		(29 "B.CrtYd" user "Package Geometry/Place Bound Bottom")
		(35 "F.Fab" user "Ref Des/Assembly Top")
		(33 "B.Fab" user "Ref Des/Assembly Bottom")
	)
	(footprint ""
		(layer "F.Cu")
		(at 122.809 -89.535 -90)
		(property "Reference" "R117"
			(at 3.429 -0.29337 90)
			(unlocked yes)
			(layer "F.SilkS")
			(effects
				(font
					(size 0.7874 0.5842)
					(thickness 0.1524)
				)
			)
		)
		(property "Value" "VAL*"
			(at 0.02032 2.13233 270)
			(unlocked yes)
			(layer "F.Fab")
			(hide yes)
			(effects
				(font
					(size 0.7874 0.5842)
					(thickness 0.1524)
				)
			)
		)
		(property "Device Type" "RESISTOR-G155-133R0-01,33OHM,1%"
			(at 0.008382 1.210564 270)
			(unlocked yes)
			(layer "F.Fab")
			(hide yes)
			(effects
				(font
					(size 0.7874 0.5842)
					(thickness 0.1524)
				)
			)
		)
		(property "User Part Number" "PARTNUM*"
			(at 0.02032 4.024884 270)
			(unlocked yes)
			(layer "Cmts.User")
			(hide yes)
			(effects
				(font
					(size 0.7874 0.5842)
					(thickness 0.1524)
				)
			)
		)
		(property "Tolerance" "TOL*"
			(at 0.044704 3.05435 270)
			(unlocked yes)
			(layer "Cmts.User")
			(hide yes)
			(effects
				(font
					(size 0.7874 0.5842)
					(thickness 0.1524)
				)
			)
		)
		(duplicate_pad_numbers_are_jumpers no)
		(fp_line
			(start -1.143 0.5588)
			(end 1.143 0.5588)
			(stroke
				(width 0.1)
				(type default)
			)
			(layer "F.SilkS")
		)
		(fp_line
			(start 1.143 0.5588)
			(end 1.143 -0.5588)
			(stroke
				(width 0.1)
				(type default)
			)
			(layer "F.SilkS")
		)
		(fp_line
			(start -1.143 -0.5588)
			(end -1.143 0.5588)
			(stroke
				(width 0.1)
				(type default)
			)
			(layer "F.SilkS")
		)
		(fp_line
			(start 1.143 -0.5588)
			(end -1.143 -0.5588)
			(stroke
				(width 0.1)
				(type default)
			)
			(layer "F.SilkS")
		)
		(fp_rect
			(start 1.143 -0.5588)
			(end -1.143 0.5588)
			(stroke
				(width 0)
				(type default)
			)
			(fill no)
			(layer "F.CrtYd")
		)
		(fp_line
			(start -0.508 0.3048)
			(end 0.508 0.3048)
			(stroke
				(width 0.1)
				(type default)
			)
			(layer "F.Fab")
		)
		(fp_line
			(start 0.508 0.3048)
			(end 0.508 -0.3048)
			(stroke
				(width 0.1)
				(type default)
			)
			(layer "F.Fab")
		)
		(fp_line
			(start -0.508 -0.3048)
			(end -0.508 0.3048)
			(stroke
				(width 0.1)
				(type default)
			)
			(layer "F.Fab")
		)
		(fp_line
			(start 0.508 -0.3048)
			(end -0.508 -0.3048)
			(stroke
				(width 0.1)
				(type default)
			)
			(layer "F.Fab")
		)
		(pad "1" smd rect
			(at -0.5334 0 270)
			(size 0.7112 0.6096)
			(layers "F.Cu" "F.Mask" "F.Paste")
			(net "GPSTP1_OUT")
		)
		(pad "2" smd rect
			(at 0.5334 0 270)
			(size 0.7112 0.6096)
			(layers "F.Cu" "F.Mask" "F.Paste")
			(net "FPGA_IN_GPSTP1_OUT")
		)
		(zone
			(layer "F.Cu")
			(hatch none 0.5)
			(connect_pads
				(clearance 0)
			)
			(min_thickness 0.25)
			(keepout
				(tracks allowed)
				(vias not_allowed)
				(pads allowed)
				(copperpour not_allowed)
				(footprints allowed)
			)
			(placement
				(enabled no)
				(sheetname "")
			)
			(fill
				(thermal_gap 0.5)
				(thermal_bridge_width 0.5)
				(island_removal_mode 0)
			)
			(polygon
				(pts
					(xy 123.1138 -89.4588) (xy 123.1138 -89.6112) (xy 122.5042 -89.6112) (xy 122.5042 -89.4588)
				)
			)
		)
	)
	(footprint ""
		(layer "F.Cu")
		(at 14.5034 -98.3488 90)
		(property "Reference" "L20"
			(at -1.1303 -1.25603 90)
			(unlocked yes)
			(layer "F.SilkS")
			(effects
				(font
					(size 0.7874 0.5842)
					(thickness 0.1524)
				)
				(justify left)
			)
		)
		(property "Value" "VAL*"
			(at -0.9398 3.70967 90)
			(unlocked yes)
			(layer "F.Fab")
			(hide yes)
			(effects
				(font
					(size 0.7874 0.5842)
					(thickness 0.1524)
				)
				(justify left)
			)
		)
		(property "Tolerance" "TOL*"
			(at -0.9906 5.00507 90)
			(unlocked yes)
			(layer "Cmts.User")
			(hide yes)
			(effects
				(font
					(size 0.7874 0.5842)
					(thickness 0.1524)
				)
				(justify left)
			)
		)
		(property "User Part Number" "PARTNUM*"
			(at -2.54 2.46507 90)
			(unlocked yes)
			(layer "Cmts.User")
			(hide yes)
			(effects
				(font
					(size 0.7874 0.5842)
					(thickness 0.1524)
				)
				(justify left)
			)
		)
		(property "Device Type" "FERRITEBEAD-G191-10101-01,26OHA"
			(at -0.9906 1.22047 90)
			(unlocked yes)
			(layer "F.Fab")
			(hide yes)
			(effects
				(font
					(size 0.7874 0.5842)
					(thickness 0.1524)
				)
				(justify left)
			)
		)
		(duplicate_pad_numbers_are_jumpers no)
		(fp_line
			(start 1.3208 -0.7112)
			(end 1.3208 0.7112)
			(stroke
				(width 0.1)
				(type default)
			)
			(layer "F.SilkS")
		)
		(fp_line
			(start -1.3208 -0.7112)
			(end 1.3208 -0.7112)
			(stroke
				(width 0.1)
				(type default)
			)
			(layer "F.SilkS")
		)
		(fp_line
			(start 1.3208 0.7112)
			(end -1.3208 0.7112)
			(stroke
				(width 0.1)
				(type default)
			)
			(layer "F.SilkS")
		)
		(fp_line
			(start -1.3208 0.7112)
			(end -1.3208 -0.7112)
			(stroke
				(width 0.1)
				(type default)
			)
			(layer "F.SilkS")
		)
		(fp_rect
			(start -1.3208 0.7112)
			(end 1.3208 -0.7112)
			(stroke
				(width 0)
				(type default)
			)
			(fill no)
			(layer "F.CrtYd")
		)
		(fp_line
			(start 0.8128 -0.4572)
			(end 0.8128 0.4572)
			(stroke
				(width 0.1)
				(type default)
			)
			(layer "F.Fab")
		)
		(fp_line
			(start -0.8128 -0.4572)
			(end 0.8128 -0.4572)
			(stroke
				(width 0.1)
				(type default)
			)
			(layer "F.Fab")
		)
		(fp_line
			(start 0.8128 0.4572)
			(end -0.8128 0.4572)
			(stroke
				(width 0.1)
				(type default)
			)
			(layer "F.Fab")
		)
		(fp_line
			(start -0.8128 0.4572)
			(end -0.8128 -0.4572)
			(stroke
				(width 0.1)
				(type default)
			)
			(layer "F.Fab")
		)
		(pad "1" smd rect
			(at -0.6858 0 90)
			(size 0.762 0.8636)
			(layers "F.Cu" "F.Mask" "F.Paste")
			(net "XP12R0V_PCIE")
		)
		(pad "2" smd rect
			(at 0.6858 0 90)
			(size 0.762 0.8636)
			(layers "F.Cu" "F.Mask" "F.Paste")
			(net "XP12R0V_IN")
		)
		(zone
			(layer "F.Cu")
			(hatch none 0.5)
			(connect_pads
				(clearance 0)
			)
			(min_thickness 0.25)
			(keepout
				(tracks not_allowed)
				(vias allowed)
				(pads allowed)
				(copperpour not_allowed)
				(footprints allowed)
			)
			(placement
				(enabled no)
				(sheetname "")
			)
			(fill
				(thermal_gap 0.5)
				(thermal_bridge_width 0.5)
				(island_removal_mode 0)
			)
			(polygon
				(pts
					(xy 14.9606 -98.1964) (xy 14.9606 -98.5012) (xy 14.0462 -98.5012) (xy 14.0462 -98.1964)
				)
			)
		)
		(zone
			(layer "F.Cu")
			(hatch none 0.5)
			(connect_pads
				(clearance 0)
			)
			(min_thickness 0.25)
			(keepout
				(tracks allowed)
				(vias not_allowed)
				(pads allowed)
				(copperpour not_allowed)
				(footprints allowed)
			)
			(placement
				(enabled no)
				(sheetname "")
			)
			(fill
				(thermal_gap 0.5)
				(thermal_bridge_width 0.5)
				(island_removal_mode 0)
			)
			(polygon
				(pts
					(xy 14.9606 -98.1964) (xy 14.9606 -98.5012) (xy 14.0462 -98.5012) (xy 14.0462 -98.1964)
				)
			)
		)
	)
)
